# BASEBOARD_FAB2 (Tioga Pass) — schematic netlist excerpt (pin names and nets, part order shuffled) for the footprints in the layout excerpt that follows; sources: Cadence DE-HDL packaged netlist, KiCad conversion of Wiwynn_Tioga_Pass_MB.brd

R1L44  RES  330 5% CHIP  pkg 0402  page 158 : A = FM_UARTSW_MSB_R_N ; B = P3V3_STBY
C7L2  CAP  10UF 4V 20% X6S  pkg 0603LF  page 234 : A = PVPP_KLM ; B = GND
C3P11  CAP  0.22UF 16V 10% X7R  pkg 0402  page 107 : A = P3E_CPU0_PE1_SS_TXP<0> ; B = P3E_CPU0_PE1_PCH_TXP<0>

(kicad_pcb
	(version 20260206)
	(generator "pcbnew")
	(generator_version "10.0")
	(general
		(thickness 1.6)
		(legacy_teardrops no)
	)
	(paper "A4")
	(title_block
		(title "Wiwynn_Tioga_Pass_MB.brd")
		(comment 1 "Tioga Pass / footprints 4544-4546 of 4770")
	)
	(layers
		(0 "F.Cu" signal "TOP")
		(4 "In1.Cu" signal "L2GND")
		(6 "In2.Cu" signal "L3")
		(8 "In3.Cu" signal "L4GND")
		(10 "In4.Cu" signal "L5")
		(12 "In5.Cu" signal "L6GND")
		(14 "In6.Cu" signal "L7VCC")
		(16 "In7.Cu" signal "L8VCC")
		(18 "In8.Cu" signal "L9GND")
		(20 "In9.Cu" signal "L10")
		(22 "In10.Cu" signal "L11GND")
		(24 "In11.Cu" signal "L12")
		(26 "In12.Cu" signal "L13GND")
		(2 "B.Cu" signal "BOTTOM")
		(9 "F.Adhes" user "F.Adhesive")
		(11 "B.Adhes" user "B.Adhesive")
		(13 "F.Paste" user "Package Geometry/Pastemask Top")
		(15 "B.Paste" user "Package Geometry/Pastemask Bottom")
		(5 "F.SilkS" user "Ref Des/Silkscreen Top")
		(7 "B.SilkS" user "Ref Des/Silkscreen Bottom")
		(1 "F.Mask" user "Board Geometry/Soldermask Top")
		(3 "B.Mask" user "Board Geometry/Soldermask Bottom")
		(17 "Dwgs.User" user "User.Drawings")
		(19 "Cmts.User" user "User.Comments")
		(21 "Eco1.User" user "User.Eco1")
		(23 "Eco2.User" user "User.Eco2")
		(25 "Edge.Cuts" user "Board Geometry/Outline")
		(27 "Margin" user)
		(31 "F.CrtYd" user "Package Geometry/Place Bound Top")
		(29 "B.CrtYd" user "Package Geometry/Place Bound Bottom")
		(35 "F.Fab" user "Ref Des/Assembly Top")
		(33 "B.Fab" user "Ref Des/Assembly Bottom")
	)
	(footprint ""
		(layer "B.Cu")
		(at 498.602 -137.287 90)
		(property "Reference" "R1L44"
			(at 0 0 90)
			(layer "B.SilkS")
			(hide yes)
			(effects
				(font
					(size 1.27 1.27)
				)
				(justify mirror)
			)
		)
		(property "Value" ""
			(at 0 0 90)
			(layer "B.Fab")
			(effects
				(font
					(size 1.27 1.27)
				)
				(justify mirror)
			)
		)
		(duplicate_pad_numbers_are_jumpers no)
		(fp_poly
			(pts
				(xy 0.2794 -0.1016) (xy -0.2794 -0.1016) (xy -0.2794 0.9906) (xy 0.2794 0.9906)
			)
			(stroke
				(width 0)
				(type default)
			)
			(fill no)
			(layer "B.CrtYd")
		)
		(fp_line
			(start 0.2794 -0.1016)
			(end 0.2794 0.9906)
			(stroke
				(width 0.1)
				(type default)
			)
			(layer "B.Fab")
		)
		(fp_line
			(start -0.2794 -0.1016)
			(end 0.2794 -0.1016)
			(stroke
				(width 0.1)
				(type default)
			)
			(layer "B.Fab")
		)
		(fp_line
			(start 0.2794 0.9906)
			(end -0.2794 0.9906)
			(stroke
				(width 0.1)
				(type default)
			)
			(layer "B.Fab")
		)
		(fp_line
			(start -0.2794 0.9906)
			(end -0.2794 -0.1016)
			(stroke
				(width 0.1)
				(type default)
			)
			(layer "B.Fab")
		)
		(pad "1" smd rect
			(at 0 0 270)
			(size 0.508 0.508)
			(layers "B.Cu" "B.Mask" "B.Paste")
			(net "FM_UARTSW_MSB_R_N")
		)
		(pad "2" smd rect
			(at 0 0.889 270)
			(size 0.508 0.508)
			(layers "B.Cu" "B.Mask" "B.Paste")
			(net "P3V3_STBY")
		)
		(zone
			(layer "B.Cu")
			(hatch none 0.5)
			(connect_pads
				(clearance 0)
			)
			(min_thickness 0.25)
			(keepout
				(tracks allowed)
				(vias not_allowed)
				(pads allowed)
				(copperpour not_allowed)
				(footprints allowed)
			)
			(placement
				(enabled no)
				(sheetname "")
			)
			(fill
				(thermal_gap 0.5)
				(thermal_bridge_width 0.5)
				(island_removal_mode 0)
			)
			(polygon
				(pts
					(xy 498.856 -137.541) (xy 498.856 -137.033) (xy 499.237 -137.033) (xy 499.237 -137.541)
				)
			)
		)
		(zone
			(layer "B.Cu")
			(hatch none 0.5)
			(connect_pads
				(clearance 0)
			)
			(min_thickness 0.25)
			(keepout
				(tracks not_allowed)
				(vias allowed)
				(pads allowed)
				(copperpour not_allowed)
				(footprints allowed)
			)
			(placement
				(enabled no)
				(sheetname "")
			)
			(fill
				(thermal_gap 0.5)
				(thermal_bridge_width 0.5)
				(island_removal_mode 0)
			)
			(polygon
				(pts
					(xy 499.237 -137.541) (xy 499.237 -137.033) (xy 498.856 -137.033) (xy 498.856 -137.541)
				)
			)
		)
	)
	(footprint ""
		(layer "B.Cu")
		(at 155.064968 -154.782012 90)
		(property "Reference" "C7L2"
			(at 0 0 90)
			(layer "B.SilkS")
			(hide yes)
			(effects
				(font
					(size 1.27 1.27)
				)
				(justify mirror)
			)
		)
		(property "Value" ""
			(at 0 0 90)
			(layer "B.Fab")
			(effects
				(font
					(size 1.27 1.27)
				)
				(justify mirror)
			)
		)
		(duplicate_pad_numbers_are_jumpers no)
		(fp_rect
			(start 0.4953 1.6002)
			(end -0.4953 -0.2032)
			(stroke
				(width 0)
				(type default)
			)
			(fill no)
			(layer "B.CrtYd")
		)
		(fp_line
			(start 0.4953 -0.2032)
			(end -0.4953 -0.2032)
			(stroke
				(width 0.1)
				(type default)
			)
			(layer "B.Fab")
		)
		(fp_line
			(start -0.4953 -0.2032)
			(end -0.4953 1.6002)
			(stroke
				(width 0.1)
				(type default)
			)
			(layer "B.Fab")
		)
		(fp_line
			(start 0.4953 1.6002)
			(end 0.4953 -0.2032)
			(stroke
				(width 0.1)
				(type default)
			)
			(layer "B.Fab")
		)
		(fp_line
			(start -0.4953 1.6002)
			(end 0.4953 1.6002)
			(stroke
				(width 0.1)
				(type default)
			)
			(layer "B.Fab")
		)
		(pad "1" smd rect
			(at 0 0 270)
			(size 0.762 0.889)
			(layers "B.Cu" "B.Mask" "B.Paste")
			(net "PVPP_KLM")
		)
		(pad "2" smd rect
			(at 0 1.397 270)
			(size 0.762 0.889)
			(layers "B.Cu" "B.Mask" "B.Paste")
			(net "GND")
		)
		(zone
			(layer "B.Cu")
			(hatch none 0.5)
			(connect_pads
				(clearance 0)
			)
			(min_thickness 0.25)
			(keepout
				(tracks not_allowed)
				(vias allowed)
				(pads allowed)
				(copperpour not_allowed)
				(footprints allowed)
			)
			(placement
				(enabled no)
				(sheetname "")
			)
			(fill
				(thermal_gap 0.5)
				(thermal_bridge_width 0.5)
				(island_removal_mode 0)
			)
			(polygon
				(pts
					(xy 156.017468 -155.163012) (xy 155.509468 -155.163012) (xy 155.509468 -154.401012) (xy 156.017468 -154.401012)
				)
			)
		)
	)
	(footprint ""
		(layer "B.Cu")
		(at 338.76996 -77.694536 180)
		(property "Reference" "C3P11"
			(at 0 0 0)
			(layer "B.SilkS")
			(hide yes)
			(effects
				(font
					(size 1.27 1.27)
				)
				(justify mirror)
			)
		)
		(property "Value" ""
			(at 0 0 0)
			(layer "B.Fab")
			(effects
				(font
					(size 1.27 1.27)
				)
				(justify mirror)
			)
		)
		(duplicate_pad_numbers_are_jumpers no)
		(fp_poly
			(pts
				(xy -0.3048 -0.1016) (xy -0.3048 0.9906) (xy 0.3048 0.9906) (xy 0.3048 -0.1016)
			)
			(stroke
				(width 0)
				(type default)
			)
			(fill no)
			(layer "B.CrtYd")
		)
		(fp_line
			(start 0.3048 0.9906)
			(end -0.3048 0.9906)
			(stroke
				(width 0.1)
				(type default)
			)
			(layer "B.Fab")
		)
		(fp_line
			(start 0.3048 -0.1016)
			(end 0.3048 0.9906)
			(stroke
				(width 0.1)
				(type default)
			)
			(layer "B.Fab")
		)
		(fp_line
			(start -0.3048 0.9906)
			(end -0.3048 -0.1016)
			(stroke
				(width 0.1)
				(type default)
			)
			(layer "B.Fab")
		)
		(fp_line
			(start -0.3048 -0.1016)
			(end 0.3048 -0.1016)
			(stroke
				(width 0.1)
				(type default)
			)
			(layer "B.Fab")
		)
		(pad "1" smd rect
			(at 0 0)
			(size 0.508 0.508)
			(layers "B.Cu" "B.Mask" "B.Paste")
			(net "P3E_CPU0_PE1_SS_TXP<0>")
		)
		(pad "2" smd rect
			(at 0 0.889)
			(size 0.508 0.508)
			(layers "B.Cu" "B.Mask" "B.Paste")
			(net "P3E_CPU0_PE1_PCH_TXP<0>")
		)
		(zone
			(layer "B.Cu")
			(hatch none 0.5)
			(connect_pads
				(clearance 0)
			)
			(min_thickness 0.25)
			(keepout
				(tracks not_allowed)
				(vias allowed)
				(pads allowed)
				(copperpour not_allowed)
				(footprints allowed)
			)
			(placement
				(enabled no)
				(sheetname "")
			)
			(fill
				(thermal_gap 0.5)
				(thermal_bridge_width 0.5)
				(island_removal_mode 0)
			)
			(polygon
				(pts
					(xy 338.51596 -78.329536) (xy 339.02396 -78.329536) (xy 339.02396 -77.948536) (xy 338.51596 -77.948536)
				)
			)
		)
		(zone
			(layer "B.Cu")
			(hatch none 0.5)
			(connect_pads
				(clearance 0)
			)
			(min_thickness 0.25)
			(keepout
				(tracks allowed)
				(vias not_allowed)
				(pads allowed)
				(copperpour not_allowed)
				(footprints allowed)
			)
			(placement
				(enabled no)
				(sheetname "")
			)
			(fill
				(thermal_gap 0.5)
				(thermal_bridge_width 0.5)
				(island_removal_mode 0)
			)
			(polygon
				(pts
					(xy 338.51596 -77.948536) (xy 339.02396 -77.948536) (xy 339.02396 -78.329536) (xy 338.51596 -78.329536)
				)
			)
		)
	)
)
